(kicad_pcb
	(version 20260206)
	(generator "pcbnew")
	(generator_version "10.0")
	(general
		(thickness 1.6)
		(legacy_teardrops no)
	)
	(paper "A4")
	(title_block
		(title "Wiwynn_Tioga_Pass_MB.brd")
		(comment 1 "Tioga Pass / footprints 1609-1615 of 4770")
	)
	(layers
		(0 "F.Cu" signal "TOP")
		(4 "In1.Cu" signal "L2GND")
		(6 "In2.Cu" signal "L3")
		(8 "In3.Cu" signal "L4GND")
		(10 "In4.Cu" signal "L5")
		(12 "In5.Cu" signal "L6GND")
		(14 "In6.Cu" signal "L7VCC")
		(16 "In7.Cu" signal "L8VCC")
		(18 "In8.Cu" signal "L9GND")
		(20 "In9.Cu" signal "L10")
		(22 "In10.Cu" signal "L11GND")
		(24 "In11.Cu" signal "L12")
		(26 "In12.Cu" signal "L13GND")
		(2 "B.Cu" signal "BOTTOM")
		(9 "F.Adhes" user "F.Adhesive")
		(11 "B.Adhes" user "B.Adhesive")
		(13 "F.Paste" user "Package Geometry/Pastemask Top")
		(15 "B.Paste" user "Package Geometry/Pastemask Bottom")
		(5 "F.SilkS" user "Ref Des/Silkscreen Top")
		(7 "B.SilkS" user "Ref Des/Silkscreen Bottom")
		(1 "F.Mask" user "Board Geometry/Soldermask Top")
		(3 "B.Mask" user "Board Geometry/Soldermask Bottom")
		(17 "Dwgs.User" user "User.Drawings")
		(19 "Cmts.User" user "User.Comments")
		(21 "Eco1.User" user "User.Eco1")
		(23 "Eco2.User" user "User.Eco2")
		(25 "Edge.Cuts" user "Board Geometry/Outline")
		(27 "Margin" user)
		(31 "F.CrtYd" user "Package Geometry/Place Bound Top")
		(29 "B.CrtYd" user "Package Geometry/Place Bound Bottom")
		(35 "F.Fab" user "Ref Des/Assembly Top")
		(33 "B.Fab" user "Ref Des/Assembly Bottom")
	)
	(footprint ""
		(layer "F.Cu")
		(at 21.863812 -68.6943)
		(property "Reference" "C1W16"
			(at -0.8382 -0.67818 0)
			(unlocked yes)
			(layer "F.SilkS")
			(effects
				(font
					(size 0.4064 0.254)
					(thickness 0.1524)
				)
				(justify left)
			)
		)
		(property "Value" ""
			(at 0 0 0)
			(layer "F.Fab")
			(effects
				(font
					(size 1.27 1.27)
				)
			)
		)
		(duplicate_pad_numbers_are_jumpers no)
		(fp_poly
			(pts
				(xy 0.3048 -0.1016) (xy 0.3048 0.9906) (xy -0.3048 0.9906) (xy -0.3048 -0.1016)
			)
			(stroke
				(width 0)
				(type default)
			)
			(fill no)
			(layer "F.CrtYd")
		)
		(fp_line
			(start -0.3048 -0.1016)
			(end -0.3048 0.9906)
			(stroke
				(width 0.1)
				(type default)
			)
			(layer "F.Fab")
		)
		(fp_line
			(start -0.3048 0.9906)
			(end 0.3048 0.9906)
			(stroke
				(width 0.1)
				(type default)
			)
			(layer "F.Fab")
		)
		(fp_line
			(start 0.3048 -0.1016)
			(end -0.3048 -0.1016)
			(stroke
				(width 0.1)
				(type default)
			)
			(layer "F.Fab")
		)
		(fp_line
			(start 0.3048 0.9906)
			(end 0.3048 -0.1016)
			(stroke
				(width 0.1)
				(type default)
			)
			(layer "F.Fab")
		)
		(pad "1" smd rect
			(at 0 0)
			(size 0.508 0.508)
			(layers "F.Cu" "F.Mask" "F.Paste")
			(net "A_HSC_TEMP")
		)
		(pad "2" smd rect
			(at 0 0.889)
			(size 0.508 0.508)
			(layers "F.Cu" "F.Mask" "F.Paste")
			(net "GND")
		)
		(zone
			(layer "F.Cu")
			(hatch none 0.5)
			(connect_pads
				(clearance 0)
			)
			(min_thickness 0.25)
			(keepout
				(tracks allowed)
				(vias not_allowed)
				(pads allowed)
				(copperpour not_allowed)
				(footprints allowed)
			)
			(placement
				(enabled no)
				(sheetname "")
			)
			(fill
				(thermal_gap 0.5)
				(thermal_bridge_width 0.5)
				(island_removal_mode 0)
			)
			(polygon
				(pts
					(xy 21.609812 -68.4403) (xy 22.117812 -68.4403) (xy 22.117812 -68.0593) (xy 21.609812 -68.0593)
				)
			)
		)
		(zone
			(layer "F.Cu")
			(hatch none 0.5)
			(connect_pads
				(clearance 0)
			)
			(min_thickness 0.25)
			(keepout
				(tracks not_allowed)
				(vias allowed)
				(pads allowed)
				(copperpour not_allowed)
				(footprints allowed)
			)
			(placement
				(enabled no)
				(sheetname "")
			)
			(fill
				(thermal_gap 0.5)
				(thermal_bridge_width 0.5)
				(island_removal_mode 0)
			)
			(polygon
				(pts
					(xy 21.609812 -68.0593) (xy 22.117812 -68.0593) (xy 22.117812 -68.4403) (xy 21.609812 -68.4403)
				)
			)
		)
	)
	(footprint ""
		(layer "F.Cu")
		(at 489.3056 -153.3398)
		(property "Reference" "CR9W1"
			(at 1.06934 -0.39116 270)
			(unlocked yes)
			(layer "F.SilkS")
			(effects
				(font
					(size 0.4064 0.254)
					(thickness 0.1524)
				)
				(justify left)
			)
		)
		(property "Value" ""
			(at 0 0 0)
			(layer "F.Fab")
			(effects
				(font
					(size 1.27 1.27)
				)
			)
		)
		(duplicate_pad_numbers_are_jumpers no)
		(fp_line
			(start -1.8161 1.664462)
			(end -1.335278 0.831596)
			(stroke
				(width 0.1524)
				(type default)
			)
			(layer "F.SilkS")
		)
		(fp_line
			(start -1.335278 -0.291846)
			(end -1.335278 0.831596)
			(stroke
				(width 0.1524)
				(type default)
			)
			(layer "F.SilkS")
		)
		(fp_line
			(start -1.335278 0.831596)
			(end -0.854456 1.664462)
			(stroke
				(width 0.1524)
				(type default)
			)
			(layer "F.SilkS")
		)
		(fp_line
			(start -1.335278 1.664462)
			(end -1.8161 1.664462)
			(stroke
				(width 0.1524)
				(type default)
			)
			(layer "F.SilkS")
		)
		(fp_line
			(start -1.335278 2.576068)
			(end -1.335278 1.664462)
			(stroke
				(width 0.1524)
				(type default)
			)
			(layer "F.SilkS")
		)
		(fp_line
			(start -0.854456 0.831596)
			(end -1.8161 0.831596)
			(stroke
				(width 0.1524)
				(type default)
			)
			(layer "F.SilkS")
		)
		(fp_line
			(start -0.854456 1.664462)
			(end -1.335278 1.664462)
			(stroke
				(width 0.1524)
				(type default)
			)
			(layer "F.SilkS")
		)
		(fp_poly
			(pts
				(xy -0.67437 0.24384) (xy -0.67437 2.04216) (xy 0.67437 2.04216) (xy 0.67437 0.24384)
			)
			(stroke
				(width 0)
				(type default)
			)
			(fill no)
			(layer "F.CrtYd")
		)
		(fp_line
			(start -1.8161 1.664462)
			(end -1.335278 0.831596)
			(stroke
				(width 0.1)
				(type default)
			)
			(layer "F.Fab")
		)
		(fp_line
			(start -1.335278 0.831596)
			(end -1.335278 -0.291846)
			(stroke
				(width 0.1)
				(type default)
			)
			(layer "F.Fab")
		)
		(fp_line
			(start -1.335278 0.831596)
			(end -0.854456 1.664462)
			(stroke
				(width 0.1)
				(type default)
			)
			(layer "F.Fab")
		)
		(fp_line
			(start -1.335278 1.664462)
			(end -1.335278 2.576068)
			(stroke
				(width 0.1)
				(type default)
			)
			(layer "F.Fab")
		)
		(fp_line
			(start -0.854456 0.831596)
			(end -1.8161 0.831596)
			(stroke
				(width 0.1)
				(type default)
			)
			(layer "F.Fab")
		)
		(fp_line
			(start -0.854456 1.664462)
			(end -1.8161 1.664462)
			(stroke
				(width 0.1)
				(type default)
			)
			(layer "F.Fab")
		)
		(fp_line
			(start -0.67437 0.24384)
			(end -0.67437 2.04216)
			(stroke
				(width 0.1)
				(type default)
			)
			(layer "F.Fab")
		)
		(fp_line
			(start -0.67437 2.04216)
			(end 0.67437 2.04216)
			(stroke
				(width 0.1)
				(type default)
			)
			(layer "F.Fab")
		)
		(fp_line
			(start 0.67437 0.24384)
			(end -0.67437 0.24384)
			(stroke
				(width 0.1)
				(type default)
			)
			(layer "F.Fab")
		)
		(fp_line
			(start 0.67437 2.04216)
			(end 0.67437 0.24384)
			(stroke
				(width 0.1)
				(type default)
			)
			(layer "F.Fab")
		)
		(pad "1" smd rect
			(at 0 0)
			(size 0.4064 1.016)
			(layers "F.Cu" "F.Mask" "F.Paste")
			(net "SPA_5V_SIN_SW")
		)
		(pad "2" smd rect
			(at 0 2.286)
			(size 0.4064 1.016)
			(layers "F.Cu" "F.Mask" "F.Paste")
			(net "SPA_5V_SIN_SW_D")
		)
	)
	(footprint ""
		(layer "F.Cu")
		(at 193.662808 -96.707452 -90)
		(property "Reference" "R4C13"
			(at 0 0 270)
			(layer "F.SilkS")
			(hide yes)
			(effects
				(font
					(size 1.27 1.27)
				)
			)
		)
		(property "Value" ""
			(at 0 0 270)
			(layer "F.Fab")
			(effects
				(font
					(size 1.27 1.27)
				)
			)
		)
		(duplicate_pad_numbers_are_jumpers no)
		(fp_poly
			(pts
				(xy -0.2794 -0.1016) (xy 0.2794 -0.1016) (xy 0.2794 0.9906) (xy -0.2794 0.9906)
			)
			(stroke
				(width 0)
				(type default)
			)
			(fill no)
			(layer "F.CrtYd")
		)
		(fp_line
			(start -0.2794 0.9906)
			(end 0.2794 0.9906)
			(stroke
				(width 0.1)
				(type default)
			)
			(layer "F.Fab")
		)
		(fp_line
			(start 0.2794 0.9906)
			(end 0.2794 -0.1016)
			(stroke
				(width 0.1)
				(type default)
			)
			(layer "F.Fab")
		)
		(fp_line
			(start -0.2794 -0.1016)
			(end -0.2794 0.9906)
			(stroke
				(width 0.1)
				(type default)
			)
			(layer "F.Fab")
		)
		(fp_line
			(start 0.2794 -0.1016)
			(end -0.2794 -0.1016)
			(stroke
				(width 0.1)
				(type default)
			)
			(layer "F.Fab")
		)
		(pad "1" smd rect
			(at 0 0 270)
			(size 0.508 0.508)
			(layers "F.Cu" "F.Mask" "F.Paste")
			(net "VR_PVSA_CPU0_OCSET")
		)
		(pad "2" smd rect
			(at 0 0.889 270)
			(size 0.508 0.508)
			(layers "F.Cu" "F.Mask" "F.Paste")
			(net "GND")
		)
		(zone
			(layer "F.Cu")
			(hatch none 0.5)
			(connect_pads
				(clearance 0)
			)
			(min_thickness 0.25)
			(keepout
				(tracks not_allowed)
				(vias allowed)
				(pads allowed)
				(copperpour not_allowed)
				(footprints allowed)
			)
			(placement
				(enabled no)
				(sheetname "")
			)
			(fill
				(thermal_gap 0.5)
				(thermal_bridge_width 0.5)
				(island_removal_mode 0)
			)
			(polygon
				(pts
					(xy 193.027808 -96.961452) (xy 193.027808 -96.453452) (xy 193.408808 -96.453452) (xy 193.408808 -96.961452)
				)
			)
		)
		(zone
			(layer "F.Cu")
			(hatch none 0.5)
			(connect_pads
				(clearance 0)
			)
			(min_thickness 0.25)
			(keepout
				(tracks allowed)
				(vias not_allowed)
				(pads allowed)
				(copperpour not_allowed)
				(footprints allowed)
			)
			(placement
				(enabled no)
				(sheetname "")
			)
			(fill
				(thermal_gap 0.5)
				(thermal_bridge_width 0.5)
				(island_removal_mode 0)
			)
			(polygon
				(pts
					(xy 193.408808 -96.961452) (xy 193.408808 -96.453452) (xy 193.027808 -96.453452) (xy 193.027808 -96.961452)
				)
			)
		)
	)
	(footprint ""
		(layer "F.Cu")
		(at 394.6525 -79.375 90)
		(property "Reference" "C7D4"
			(at 0 0 90)
			(layer "F.SilkS")
			(hide yes)
			(effects
				(font
					(size 1.27 1.27)
				)
			)
		)
		(property "Value" ""
			(at 0 0 90)
			(layer "F.Fab")
			(effects
				(font
					(size 1.27 1.27)
				)
			)
		)
		(duplicate_pad_numbers_are_jumpers no)
		(fp_poly
			(pts
				(xy 0.3048 -0.1016) (xy 0.3048 0.9906) (xy -0.3048 0.9906) (xy -0.3048 -0.1016)
			)
			(stroke
				(width 0)
				(type default)
			)
			(fill no)
			(layer "F.CrtYd")
		)
		(fp_line
			(start 0.3048 -0.1016)
			(end -0.3048 -0.1016)
			(stroke
				(width 0.1)
				(type default)
			)
			(layer "F.Fab")
		)
		(fp_line
			(start -0.3048 -0.1016)
			(end -0.3048 0.9906)
			(stroke
				(width 0.1)
				(type default)
			)
			(layer "F.Fab")
		)
		(fp_line
			(start 0.3048 0.9906)
			(end 0.3048 -0.1016)
			(stroke
				(width 0.1)
				(type default)
			)
			(layer "F.Fab")
		)
		(fp_line
			(start -0.3048 0.9906)
			(end 0.3048 0.9906)
			(stroke
				(width 0.1)
				(type default)
			)
			(layer "F.Fab")
		)
		(pad "1" smd rect
			(at 0 0 90)
			(size 0.508 0.508)
			(layers "F.Cu" "F.Mask" "F.Paste")
			(net "P3V3")
		)
		(pad "2" smd rect
			(at 0 0.889 90)
			(size 0.508 0.508)
			(layers "F.Cu" "F.Mask" "F.Paste")
			(net "GND")
		)
		(zone
			(layer "F.Cu")
			(hatch none 0.5)
			(connect_pads
				(clearance 0)
			)
			(min_thickness 0.25)
			(keepout
				(tracks allowed)
				(vias not_allowed)
				(pads allowed)
				(copperpour not_allowed)
				(footprints allowed)
			)
			(placement
				(enabled no)
				(sheetname "")
			)
			(fill
				(thermal_gap 0.5)
				(thermal_bridge_width 0.5)
				(island_removal_mode 0)
			)
			(polygon
				(pts
					(xy 394.9065 -79.121) (xy 394.9065 -79.629) (xy 395.2875 -79.629) (xy 395.2875 -79.121)
				)
			)
		)
		(zone
			(layer "F.Cu")
			(hatch none 0.5)
			(connect_pads
				(clearance 0)
			)
			(min_thickness 0.25)
			(keepout
				(tracks not_allowed)
				(vias allowed)
				(pads allowed)
				(copperpour not_allowed)
				(footprints allowed)
			)
			(placement
				(enabled no)
				(sheetname "")
			)
			(fill
				(thermal_gap 0.5)
				(thermal_bridge_width 0.5)
				(island_removal_mode 0)
			)
			(polygon
				(pts
					(xy 395.2875 -79.121) (xy 395.2875 -79.629) (xy 394.9065 -79.629) (xy 394.9065 -79.121)
				)
			)
		)
	)
	(footprint ""
		(layer "F.Cu")
		(at 363.8804 -135.9916 90)
		(property "Reference" "R12W28"
			(at -0.8382 -0.67818 90)
			(unlocked yes)
			(layer "F.SilkS")
			(effects
				(font
					(size 0.4064 0.254)
					(thickness 0.1524)
				)
				(justify left)
			)
		)
		(property "Value" ""
			(at 0 0 90)
			(layer "F.Fab")
			(effects
				(font
					(size 1.27 1.27)
				)
			)
		)
		(duplicate_pad_numbers_are_jumpers no)
		(fp_poly
			(pts
				(xy -0.2794 -0.1016) (xy 0.2794 -0.1016) (xy 0.2794 0.9906) (xy -0.2794 0.9906)
			)
			(stroke
				(width 0)
				(type default)
			)
			(fill no)
			(layer "F.CrtYd")
		)
		(fp_line
			(start 0.2794 -0.1016)
			(end -0.2794 -0.1016)
			(stroke
				(width 0.1)
				(type default)
			)
			(layer "F.Fab")
		)
		(fp_line
			(start -0.2794 -0.1016)
			(end -0.2794 0.9906)
			(stroke
				(width 0.1)
				(type default)
			)
			(layer "F.Fab")
		)
		(fp_line
			(start 0.2794 0.9906)
			(end 0.2794 -0.1016)
			(stroke
				(width 0.1)
				(type default)
			)
			(layer "F.Fab")
		)
		(fp_line
			(start -0.2794 0.9906)
			(end 0.2794 0.9906)
			(stroke
				(width 0.1)
				(type default)
			)
			(layer "F.Fab")
		)
		(pad "1" smd rect
			(at 0 0 90)
			(size 0.508 0.508)
			(layers "F.Cu" "F.Mask" "F.Paste")
			(net "PU_VR_PVDDQ_DEF_FAULT1")
		)
		(pad "2" smd rect
			(at 0 0.889 90)
			(size 0.508 0.508)
			(layers "F.Cu" "F.Mask" "F.Paste")
			(net "PWRGD_PVDDQ_DEF")
		)
		(zone
			(layer "F.Cu")
			(hatch none 0.5)
			(connect_pads
				(clearance 0)
			)
			(min_thickness 0.25)
			(keepout
				(tracks allowed)
				(vias not_allowed)
				(pads allowed)
				(copperpour not_allowed)
				(footprints allowed)
			)
			(placement
				(enabled no)
				(sheetname "")
			)
			(fill
				(thermal_gap 0.5)
				(thermal_bridge_width 0.5)
				(island_removal_mode 0)
			)
			(polygon
				(pts
					(xy 364.1344 -135.7376) (xy 364.1344 -136.2456) (xy 364.5154 -136.2456) (xy 364.5154 -135.7376)
				)
			)
		)
		(zone
			(layer "F.Cu")
			(hatch none 0.5)
			(connect_pads
				(clearance 0)
			)
			(min_thickness 0.25)
			(keepout
				(tracks not_allowed)
				(vias allowed)
				(pads allowed)
				(copperpour not_allowed)
				(footprints allowed)
			)
			(placement
				(enabled no)
				(sheetname "")
			)
			(fill
				(thermal_gap 0.5)
				(thermal_bridge_width 0.5)
				(island_removal_mode 0)
			)
			(polygon
				(pts
					(xy 364.5154 -135.7376) (xy 364.5154 -136.2456) (xy 364.1344 -136.2456) (xy 364.1344 -135.7376)
				)
			)
		)
	)
	(footprint ""
		(layer "F.Cu")
		(at 399.770092 -0.998474 90)
		(property "Reference" "R7G14"
			(at 0 0 90)
			(layer "F.SilkS")
			(hide yes)
			(effects
				(font
					(size 1.27 1.27)
				)
			)
		)
		(property "Value" ""
			(at 0 0 90)
			(layer "F.Fab")
			(effects
				(font
					(size 1.27 1.27)
				)
			)
		)
		(duplicate_pad_numbers_are_jumpers no)
		(fp_poly
			(pts
				(xy -0.2794 -0.1016) (xy 0.2794 -0.1016) (xy 0.2794 0.9906) (xy -0.2794 0.9906)
			)
			(stroke
				(width 0)
				(type default)
			)
			(fill no)
			(layer "F.CrtYd")
		)
		(fp_line
			(start 0.2794 -0.1016)
			(end -0.2794 -0.1016)
			(stroke
				(width 0.1)
				(type default)
			)
			(layer "F.Fab")
		)
		(fp_line
			(start -0.2794 -0.1016)
			(end -0.2794 0.9906)
			(stroke
				(width 0.1)
				(type default)
			)
			(layer "F.Fab")
		)
		(fp_line
			(start 0.2794 0.9906)
			(end 0.2794 -0.1016)
			(stroke
				(width 0.1)
				(type default)
			)
			(layer "F.Fab")
		)
		(fp_line
			(start -0.2794 0.9906)
			(end 0.2794 0.9906)
			(stroke
				(width 0.1)
				(type default)
			)
			(layer "F.Fab")
		)
		(pad "1" smd rect
			(at 0 0 90)
			(size 0.508 0.508)
			(layers "F.Cu" "F.Mask" "F.Paste")
			(net "JTAG_PLD_TDO_MUX_R")
		)
		(pad "2" smd rect
			(at 0 0.889 90)
			(size 0.508 0.508)
			(layers "F.Cu" "F.Mask" "F.Paste")
			(net "JTAG_PLD_TDO_MUX")
		)
		(zone
			(layer "F.Cu")
			(hatch none 0.5)
			(connect_pads
				(clearance 0)
			)
			(min_thickness 0.25)
			(keepout
				(tracks allowed)
				(vias not_allowed)
				(pads allowed)
				(copperpour not_allowed)
				(footprints allowed)
			)
			(placement
				(enabled no)
				(sheetname "")
			)
			(fill
				(thermal_gap 0.5)
				(thermal_bridge_width 0.5)
				(island_removal_mode 0)
			)
			(polygon
				(pts
					(xy 400.024092 -0.744474) (xy 400.024092 -1.252474) (xy 400.405092 -1.252474) (xy 400.405092 -0.744474)
				)
			)
		)
		(zone
			(layer "F.Cu")
			(hatch none 0.5)
			(connect_pads
				(clearance 0)
			)
			(min_thickness 0.25)
			(keepout
				(tracks not_allowed)
				(vias allowed)
				(pads allowed)
				(copperpour not_allowed)
				(footprints allowed)
			)
			(placement
				(enabled no)
				(sheetname "")
			)
			(fill
				(thermal_gap 0.5)
				(thermal_bridge_width 0.5)
				(island_removal_mode 0)
			)
			(polygon
				(pts
					(xy 400.405092 -0.744474) (xy 400.405092 -1.252474) (xy 400.024092 -1.252474) (xy 400.024092 -0.744474)
				)
			)
		)
	)
	(footprint ""
		(layer "F.Cu")
		(at 205.036928 -73.287382)
		(property "Reference" "L4D2"
			(at 3.378708 -4.251706 0)
			(unlocked yes)
			(layer "F.SilkS")
			(effects
				(font
					(size 0.4064 0.254)
					(thickness 0.1524)
				)
			)
		)
		(property "Value" ""
			(at 0 0 0)
			(layer "F.Fab")
			(effects
				(font
					(size 1.27 1.27)
				)
			)
		)
		(duplicate_pad_numbers_are_jumpers no)
		(fp_line
			(start -1.1303 -3.199892)
			(end 8.3693 -3.199892)
			(stroke
				(width 0.1524)
				(type default)
			)
			(layer "F.SilkS")
		)
		(fp_line
			(start -1.1303 -1.6637)
			(end -1.1303 -3.199892)
			(stroke
				(width 0.1524)
				(type default)
			)
			(layer "F.SilkS")
		)
		(fp_line
			(start -1.1303 3.199892)
			(end -1.1303 1.6637)
			(stroke
				(width 0.1524)
				(type default)
			)
			(layer "F.SilkS")
		)
		(fp_line
			(start 8.3693 -3.199892)
			(end 8.3693 -1.6637)
			(stroke
				(width 0.1524)
				(type default)
			)
			(layer "F.SilkS")
		)
		(fp_line
			(start 8.3693 1.6637)
			(end 8.3693 3.199892)
			(stroke
				(width 0.1524)
				(type default)
			)
			(layer "F.SilkS")
		)
		(fp_line
			(start 8.3693 3.199892)
			(end -1.1303 3.199892)
			(stroke
				(width 0.1524)
				(type default)
			)
			(layer "F.SilkS")
		)
		(fp_rect
			(start -1.1303 3.199892)
			(end 8.3693 -3.199892)
			(stroke
				(width 0)
				(type default)
			)
			(fill no)
			(layer "F.CrtYd")
		)
		(fp_line
			(start -1.1303 -3.199892)
			(end 8.3693 -3.199892)
			(stroke
				(width 0.1)
				(type default)
			)
			(layer "F.Fab")
		)
		(fp_line
			(start -1.1303 3.199892)
			(end -1.1303 -3.199892)
			(stroke
				(width 0.1)
				(type default)
			)
			(layer "F.Fab")
		)
		(fp_line
			(start 8.3693 -3.199892)
			(end 8.3693 3.199892)
			(stroke
				(width 0.1)
				(type default)
			)
			(layer "F.Fab")
		)
		(fp_line
			(start 8.3693 3.199892)
			(end -1.1303 3.199892)
			(stroke
				(width 0.1)
				(type default)
			)
			(layer "F.Fab")
		)
		(pad "1" smd rect
			(at 0 0)
			(size 3.683 2.667)
			(layers "F.Cu" "F.Mask" "F.Paste")
			(net "VR_PVCCIN_CPU0_PHASE3")
		)
		(pad "2" smd rect
			(at 7.239 0)
			(size 3.683 2.667)
			(layers "F.Cu" "F.Mask" "F.Paste")
			(net "PVCCIN_CPU0")
		)
	)
)
